(kicad_pcb
	(version 20260206)
	(generator "pcbnew")
	(generator_version "10.0")
	(general
		(thickness 1.6)
		(legacy_teardrops no)
	)
	(paper "A4")
	(title_block
		(title "Wiwynn_Tioga_Pass_MB.brd")
		(comment 1 "Tioga Pass / footprint 3254 of 4770 (J6M1), pads 124-243 of 291")
	)
	(layers
		(0 "F.Cu" signal "TOP")
		(4 "In1.Cu" signal "L2GND")
		(6 "In2.Cu" signal "L3")
		(8 "In3.Cu" signal "L4GND")
		(10 "In4.Cu" signal "L5")
		(12 "In5.Cu" signal "L6GND")
		(14 "In6.Cu" signal "L7VCC")
		(16 "In7.Cu" signal "L8VCC")
		(18 "In8.Cu" signal "L9GND")
		(20 "In9.Cu" signal "L10")
		(22 "In10.Cu" signal "L11GND")
		(24 "In11.Cu" signal "L12")
		(26 "In12.Cu" signal "L13GND")
		(2 "B.Cu" signal "BOTTOM")
		(9 "F.Adhes" user "F.Adhesive")
		(11 "B.Adhes" user "B.Adhesive")
		(13 "F.Paste" user "Package Geometry/Pastemask Top")
		(15 "B.Paste" user "Package Geometry/Pastemask Bottom")
		(5 "F.SilkS" user "Ref Des/Silkscreen Top")
		(7 "B.SilkS" user "Ref Des/Silkscreen Bottom")
		(1 "F.Mask" user "Board Geometry/Soldermask Top")
		(3 "B.Mask" user "Board Geometry/Soldermask Bottom")
		(17 "Dwgs.User" user "User.Drawings")
		(19 "Cmts.User" user "User.Comments")
		(21 "Eco1.User" user "User.Eco1")
		(23 "Eco2.User" user "User.Eco2")
		(25 "Edge.Cuts" user "Board Geometry/Outline")
		(27 "Margin" user)
		(31 "F.CrtYd" user "Package Geometry/Place Bound Top")
		(29 "B.CrtYd" user "Package Geometry/Place Bound Bottom")
		(35 "F.Fab" user "Ref Des/Assembly Top")
		(33 "B.Fab" user "Ref Des/Assembly Bottom")
	)
	(footprint ""
		(layer "B.Cu")
		(at 194.700398 -132.876036 90)
		(property "Reference" "J6M1"
			(at 2.352548 37.96411 0)
			(unlocked yes)
			(layer "B.SilkS")
			(effects
				(font
					(size 0.7874 0.5842)
					(thickness 0.1524)
				)
				(justify left mirror)
			)
		)
		(property "Value" ""
			(at 0 0 90)
			(layer "B.Fab")
			(effects
				(font
					(size 1.27 1.27)
				)
				(justify mirror)
			)
		)
		(duplicate_pad_numbers_are_jumpers no)
		(pad "121" smd rect
			(at 0 107.100116 270)
			(size 1.8034 0.508)
			(layers "B.Cu" "B.Mask" "B.Paste")
			(net "M_D_DQS_DP<15>")
		)
		(pad "122" smd rect
			(at 0 107.95 270)
			(size 1.8034 0.508)
			(layers "B.Cu" "B.Mask" "B.Paste")
			(net "M_D_DQS_DN<15>")
		)
		(pad "123" smd rect
			(at 0 108.799884 270)
			(size 1.8034 0.508)
			(layers "B.Cu" "B.Mask" "B.Paste")
			(net "GND")
		)
		(pad "124" smd rect
			(at 0 109.650022 270)
			(size 1.8034 0.508)
			(layers "B.Cu" "B.Mask" "B.Paste")
			(net "M_D_DQ<54>")
		)
		(pad "125" smd rect
			(at 0 110.499906 270)
			(size 1.8034 0.508)
			(layers "B.Cu" "B.Mask" "B.Paste")
			(net "GND")
		)
		(pad "126" smd rect
			(at 0 111.350044 270)
			(size 1.8034 0.508)
			(layers "B.Cu" "B.Mask" "B.Paste")
			(net "M_D_DQ<50>")
		)
		(pad "127" smd rect
			(at 0 112.199928 270)
			(size 1.8034 0.508)
			(layers "B.Cu" "B.Mask" "B.Paste")
			(net "GND")
		)
		(pad "128" smd rect
			(at 0 113.050066 270)
			(size 1.8034 0.508)
			(layers "B.Cu" "B.Mask" "B.Paste")
			(net "M_D_DQ<60>")
		)
		(pad "129" smd rect
			(at 0 113.89995 270)
			(size 1.8034 0.508)
			(layers "B.Cu" "B.Mask" "B.Paste")
			(net "GND")
		)
		(pad "130" smd rect
			(at 0 114.750088 270)
			(size 1.8034 0.508)
			(layers "B.Cu" "B.Mask" "B.Paste")
			(net "M_D_DQ<56>")
		)
		(pad "131" smd rect
			(at 0 115.599972 270)
			(size 1.8034 0.508)
			(layers "B.Cu" "B.Mask" "B.Paste")
			(net "GND")
		)
		(pad "132" smd rect
			(at 0 116.45011 270)
			(size 1.8034 0.508)
			(layers "B.Cu" "B.Mask" "B.Paste")
			(net "M_D_DQS_DP<16>")
		)
		(pad "133" smd rect
			(at 0 117.299994 270)
			(size 1.8034 0.508)
			(layers "B.Cu" "B.Mask" "B.Paste")
			(net "M_D_DQS_DN<16>")
		)
		(pad "134" smd rect
			(at 0 118.149878 270)
			(size 1.8034 0.508)
			(layers "B.Cu" "B.Mask" "B.Paste")
			(net "GND")
		)
		(pad "135" smd rect
			(at 0 119.000016 270)
			(size 1.8034 0.508)
			(layers "B.Cu" "B.Mask" "B.Paste")
			(net "M_D_DQ<62>")
		)
		(pad "136" smd rect
			(at 0 119.8499 270)
			(size 1.8034 0.508)
			(layers "B.Cu" "B.Mask" "B.Paste")
			(net "GND")
		)
		(pad "137" smd rect
			(at 0 120.700038 270)
			(size 1.8034 0.508)
			(layers "B.Cu" "B.Mask" "B.Paste")
			(net "M_D_DQ<58>")
		)
		(pad "138" smd rect
			(at 0 121.549922 270)
			(size 1.8034 0.508)
			(layers "B.Cu" "B.Mask" "B.Paste")
			(net "GND")
		)
		(pad "139" smd rect
			(at 0 122.40006 270)
			(size 1.8034 0.508)
			(layers "B.Cu" "B.Mask" "B.Paste")
			(net "PVPP_DEF")
		)
		(pad "140" smd rect
			(at 0 123.249944 270)
			(size 1.8034 0.508)
			(layers "B.Cu" "B.Mask" "B.Paste")
			(net "GND")
		)
		(pad "141" smd rect
			(at 0 124.100082 270)
			(size 1.8034 0.508)
			(layers "B.Cu" "B.Mask" "B.Paste")
			(net "SMB_DDR_DEF_VPP_SCL")
		)
		(pad "142" smd rect
			(at 0 124.949966 270)
			(size 1.8034 0.508)
			(layers "B.Cu" "B.Mask" "B.Paste")
			(net "PVPP_DEF")
		)
		(pad "143" smd rect
			(at 0 125.800104 270)
			(size 1.8034 0.508)
			(layers "B.Cu" "B.Mask" "B.Paste")
			(net "PVPP_DEF")
		)
		(pad "144" smd rect
			(at 0 126.649988 270)
			(size 1.8034 0.508)
			(layers "B.Cu" "B.Mask" "B.Paste")
			(net "TP_CH_D_DIMM_D1_RFU_2")
		)
		(pad "145" smd rect
			(at -4.59994 0 270)
			(size 1.8034 0.508)
			(layers "B.Cu" "B.Mask" "B.Paste")
			(net "P12V_NVDIMM_DEF")
		)
		(pad "146" smd rect
			(at -4.59994 0.849884 270)
			(size 1.8034 0.508)
			(layers "B.Cu" "B.Mask" "B.Paste")
			(net "M_D_VREF")
		)
		(pad "147" smd rect
			(at -4.59994 1.700022 270)
			(size 1.8034 0.508)
			(layers "B.Cu" "B.Mask" "B.Paste")
			(net "GND")
		)
		(pad "148" smd rect
			(at -4.59994 2.549906 270)
			(size 1.8034 0.508)
			(layers "B.Cu" "B.Mask" "B.Paste")
			(net "M_D_DQ<5>")
		)
		(pad "149" smd rect
			(at -4.59994 3.400044 270)
			(size 1.8034 0.508)
			(layers "B.Cu" "B.Mask" "B.Paste")
			(net "GND")
		)
		(pad "150" smd rect
			(at -4.59994 4.249928 270)
			(size 1.8034 0.508)
			(layers "B.Cu" "B.Mask" "B.Paste")
			(net "M_D_DQ<1>")
		)
		(pad "151" smd rect
			(at -4.59994 5.100066 270)
			(size 1.8034 0.508)
			(layers "B.Cu" "B.Mask" "B.Paste")
			(net "GND")
		)
		(pad "152" smd rect
			(at -4.59994 5.94995 270)
			(size 1.8034 0.508)
			(layers "B.Cu" "B.Mask" "B.Paste")
			(net "M_D_DQS_DN<0>")
		)
		(pad "153" smd rect
			(at -4.59994 6.800088 270)
			(size 1.8034 0.508)
			(layers "B.Cu" "B.Mask" "B.Paste")
			(net "M_D_DQS_DP<0>")
		)
		(pad "154" smd rect
			(at -4.59994 7.649972 270)
			(size 1.8034 0.508)
			(layers "B.Cu" "B.Mask" "B.Paste")
			(net "GND")
		)
		(pad "155" smd rect
			(at -4.59994 8.50011 270)
			(size 1.8034 0.508)
			(layers "B.Cu" "B.Mask" "B.Paste")
			(net "M_D_DQ<7>")
		)
		(pad "156" smd rect
			(at -4.59994 9.349994 270)
			(size 1.8034 0.508)
			(layers "B.Cu" "B.Mask" "B.Paste")
			(net "GND")
		)
		(pad "157" smd rect
			(at -4.59994 10.199878 270)
			(size 1.8034 0.508)
			(layers "B.Cu" "B.Mask" "B.Paste")
			(net "M_D_DQ<3>")
		)
		(pad "158" smd rect
			(at -4.59994 11.050016 270)
			(size 1.8034 0.508)
			(layers "B.Cu" "B.Mask" "B.Paste")
			(net "GND")
		)
		(pad "159" smd rect
			(at -4.59994 11.8999 270)
			(size 1.8034 0.508)
			(layers "B.Cu" "B.Mask" "B.Paste")
			(net "M_D_DQ<13>")
		)
		(pad "160" smd rect
			(at -4.59994 12.750038 270)
			(size 1.8034 0.508)
			(layers "B.Cu" "B.Mask" "B.Paste")
			(net "GND")
		)
		(pad "161" smd rect
			(at -4.59994 13.599922 270)
			(size 1.8034 0.508)
			(layers "B.Cu" "B.Mask" "B.Paste")
			(net "M_D_DQ<9>")
		)
		(pad "162" smd rect
			(at -4.59994 14.45006 270)
			(size 1.8034 0.508)
			(layers "B.Cu" "B.Mask" "B.Paste")
			(net "GND")
		)
		(pad "163" smd rect
			(at -4.59994 15.299944 270)
			(size 1.8034 0.508)
			(layers "B.Cu" "B.Mask" "B.Paste")
			(net "M_D_DQS_DN<1>")
		)
		(pad "164" smd rect
			(at -4.59994 16.150082 270)
			(size 1.8034 0.508)
			(layers "B.Cu" "B.Mask" "B.Paste")
			(net "M_D_DQS_DP<1>")
		)
		(pad "165" smd rect
			(at -4.59994 16.999966 270)
			(size 1.8034 0.508)
			(layers "B.Cu" "B.Mask" "B.Paste")
			(net "GND")
		)
		(pad "166" smd rect
			(at -4.59994 17.850104 270)
			(size 1.8034 0.508)
			(layers "B.Cu" "B.Mask" "B.Paste")
			(net "M_D_DQ<15>")
		)
		(pad "167" smd rect
			(at -4.59994 18.699988 270)
			(size 1.8034 0.508)
			(layers "B.Cu" "B.Mask" "B.Paste")
			(net "GND")
		)
		(pad "168" smd rect
			(at -4.59994 19.550126 270)
			(size 1.8034 0.508)
			(layers "B.Cu" "B.Mask" "B.Paste")
			(net "M_D_DQ<11>")
		)
		(pad "169" smd rect
			(at -4.59994 20.40001 270)
			(size 1.8034 0.508)
			(layers "B.Cu" "B.Mask" "B.Paste")
			(net "GND")
		)
		(pad "170" smd rect
			(at -4.59994 21.249894 270)
			(size 1.8034 0.508)
			(layers "B.Cu" "B.Mask" "B.Paste")
			(net "M_D_DQ<21>")
		)
		(pad "171" smd rect
			(at -4.59994 22.100032 270)
			(size 1.8034 0.508)
			(layers "B.Cu" "B.Mask" "B.Paste")
			(net "GND")
		)
		(pad "172" smd rect
			(at -4.59994 22.949916 270)
			(size 1.8034 0.508)
			(layers "B.Cu" "B.Mask" "B.Paste")
			(net "M_D_DQ<17>")
		)
		(pad "173" smd rect
			(at -4.59994 23.800054 270)
			(size 1.8034 0.508)
			(layers "B.Cu" "B.Mask" "B.Paste")
			(net "GND")
		)
		(pad "174" smd rect
			(at -4.59994 24.649938 270)
			(size 1.8034 0.508)
			(layers "B.Cu" "B.Mask" "B.Paste")
			(net "M_D_DQS_DN<2>")
		)
		(pad "175" smd rect
			(at -4.59994 25.500076 270)
			(size 1.8034 0.508)
			(layers "B.Cu" "B.Mask" "B.Paste")
			(net "M_D_DQS_DP<2>")
		)
		(pad "176" smd rect
			(at -4.59994 26.34996 270)
			(size 1.8034 0.508)
			(layers "B.Cu" "B.Mask" "B.Paste")
			(net "GND")
		)
		(pad "177" smd rect
			(at -4.59994 27.200098 270)
			(size 1.8034 0.508)
			(layers "B.Cu" "B.Mask" "B.Paste")
			(net "M_D_DQ<23>")
		)
		(pad "178" smd rect
			(at -4.59994 28.049982 270)
			(size 1.8034 0.508)
			(layers "B.Cu" "B.Mask" "B.Paste")
			(net "GND")
		)
		(pad "179" smd rect
			(at -4.59994 28.90012 270)
			(size 1.8034 0.508)
			(layers "B.Cu" "B.Mask" "B.Paste")
			(net "M_D_DQ<19>")
		)
		(pad "180" smd rect
			(at -4.59994 29.750004 270)
			(size 1.8034 0.508)
			(layers "B.Cu" "B.Mask" "B.Paste")
			(net "GND")
		)
		(pad "181" smd rect
			(at -4.59994 30.599888 270)
			(size 1.8034 0.508)
			(layers "B.Cu" "B.Mask" "B.Paste")
			(net "M_D_DQ<29>")
		)
		(pad "182" smd rect
			(at -4.59994 31.450026 270)
			(size 1.8034 0.508)
			(layers "B.Cu" "B.Mask" "B.Paste")
			(net "GND")
		)
		(pad "183" smd rect
			(at -4.59994 32.29991 270)
			(size 1.8034 0.508)
			(layers "B.Cu" "B.Mask" "B.Paste")
			(net "M_D_DQ<25>")
		)
		(pad "184" smd rect
			(at -4.59994 33.150048 270)
			(size 1.8034 0.508)
			(layers "B.Cu" "B.Mask" "B.Paste")
			(net "GND")
		)
		(pad "185" smd rect
			(at -4.59994 33.999932 270)
			(size 1.8034 0.508)
			(layers "B.Cu" "B.Mask" "B.Paste")
			(net "M_D_DQS_DN<3>")
		)
		(pad "186" smd rect
			(at -4.59994 34.85007 270)
			(size 1.8034 0.508)
			(layers "B.Cu" "B.Mask" "B.Paste")
			(net "M_D_DQS_DP<3>")
		)
		(pad "187" smd rect
			(at -4.59994 35.699954 270)
			(size 1.8034 0.508)
			(layers "B.Cu" "B.Mask" "B.Paste")
			(net "GND")
		)
		(pad "188" smd rect
			(at -4.59994 36.550092 270)
			(size 1.8034 0.508)
			(layers "B.Cu" "B.Mask" "B.Paste")
			(net "M_D_DQ<31>")
		)
		(pad "189" smd rect
			(at -4.59994 37.399976 270)
			(size 1.8034 0.508)
			(layers "B.Cu" "B.Mask" "B.Paste")
			(net "GND")
		)
		(pad "190" smd rect
			(at -4.59994 38.250114 270)
			(size 1.8034 0.508)
			(layers "B.Cu" "B.Mask" "B.Paste")
			(net "M_D_DQ<27>")
		)
		(pad "191" smd rect
			(at -4.59994 39.099998 270)
			(size 1.8034 0.508)
			(layers "B.Cu" "B.Mask" "B.Paste")
			(net "GND")
		)
		(pad "192" smd rect
			(at -4.59994 39.949882 270)
			(size 1.8034 0.508)
			(layers "B.Cu" "B.Mask" "B.Paste")
			(net "M_D_ECC<5>")
		)
		(pad "193" smd rect
			(at -4.59994 40.80002 270)
			(size 1.8034 0.508)
			(layers "B.Cu" "B.Mask" "B.Paste")
			(net "GND")
		)
		(pad "194" smd rect
			(at -4.59994 41.649904 270)
			(size 1.8034 0.508)
			(layers "B.Cu" "B.Mask" "B.Paste")
			(net "M_D_ECC<1>")
		)
		(pad "195" smd rect
			(at -4.59994 42.500042 270)
			(size 1.8034 0.508)
			(layers "B.Cu" "B.Mask" "B.Paste")
			(net "GND")
		)
		(pad "196" smd rect
			(at -4.59994 43.349926 270)
			(size 1.8034 0.508)
			(layers "B.Cu" "B.Mask" "B.Paste")
			(net "M_D_DQS_DN<8>")
		)
		(pad "197" smd rect
			(at -4.59994 44.200064 270)
			(size 1.8034 0.508)
			(layers "B.Cu" "B.Mask" "B.Paste")
			(net "M_D_DQS_DP<8>")
		)
		(pad "198" smd rect
			(at -4.59994 45.049948 270)
			(size 1.8034 0.508)
			(layers "B.Cu" "B.Mask" "B.Paste")
			(net "GND")
		)
		(pad "199" smd rect
			(at -4.59994 45.900086 270)
			(size 1.8034 0.508)
			(layers "B.Cu" "B.Mask" "B.Paste")
			(net "M_D_ECC<7>")
		)
		(pad "200" smd rect
			(at -4.59994 46.74997 270)
			(size 1.8034 0.508)
			(layers "B.Cu" "B.Mask" "B.Paste")
			(net "GND")
		)
		(pad "201" smd rect
			(at -4.59994 47.600108 270)
			(size 1.8034 0.508)
			(layers "B.Cu" "B.Mask" "B.Paste")
			(net "M_D_ECC<3>")
		)
		(pad "202" smd rect
			(at -4.59994 48.449992 270)
			(size 1.8034 0.508)
			(layers "B.Cu" "B.Mask" "B.Paste")
			(net "GND")
		)
		(pad "203" smd rect
			(at -4.59994 49.299876 270)
			(size 1.8034 0.508)
			(layers "B.Cu" "B.Mask" "B.Paste")
			(net "M_D_CKE<3>")
		)
		(pad "204" smd rect
			(at -4.59994 50.150014 270)
			(size 1.8034 0.508)
			(layers "B.Cu" "B.Mask" "B.Paste")
			(net "PVDDQ_DEF")
		)
		(pad "205" smd rect
			(at -4.59994 50.999898 270)
			(size 1.8034 0.508)
			(layers "B.Cu" "B.Mask" "B.Paste")
			(net "TP_CH_D_DIMM_D1_RFU_0")
		)
		(pad "206" smd rect
			(at -4.59994 51.850036 270)
			(size 1.8034 0.508)
			(layers "B.Cu" "B.Mask" "B.Paste")
			(net "PVDDQ_DEF")
		)
		(pad "207" smd rect
			(at -4.59994 52.69992 270)
			(size 1.8034 0.508)
			(layers "B.Cu" "B.Mask" "B.Paste")
			(net "M_D_BG<1>")
		)
		(pad "208" smd rect
			(at -4.59994 53.550058 270)
			(size 1.8034 0.508)
			(layers "B.Cu" "B.Mask" "B.Paste")
			(net "M_D_ALERT_N")
		)
		(pad "209" smd rect
			(at -4.59994 54.399942 270)
			(size 1.8034 0.508)
			(layers "B.Cu" "B.Mask" "B.Paste")
			(net "PVDDQ_DEF")
		)
		(pad "210" smd rect
			(at -4.59994 55.25008 270)
			(size 1.8034 0.508)
			(layers "B.Cu" "B.Mask" "B.Paste")
			(net "M_D_MA<11>")
		)
		(pad "211" smd rect
			(at -4.59994 56.099964 270)
			(size 1.8034 0.508)
			(layers "B.Cu" "B.Mask" "B.Paste")
			(net "M_D_MA<7>")
		)
		(pad "212" smd rect
			(at -4.59994 56.950102 270)
			(size 1.8034 0.508)
			(layers "B.Cu" "B.Mask" "B.Paste")
			(net "PVDDQ_DEF")
		)
		(pad "213" smd rect
			(at -4.59994 57.799986 270)
			(size 1.8034 0.508)
			(layers "B.Cu" "B.Mask" "B.Paste")
			(net "M_D_MA<5>")
		)
		(pad "214" smd rect
			(at -4.59994 58.650124 270)
			(size 1.8034 0.508)
			(layers "B.Cu" "B.Mask" "B.Paste")
			(net "M_D_MA<4>")
		)
		(pad "215" smd rect
			(at -4.59994 59.500008 270)
			(size 1.8034 0.508)
			(layers "B.Cu" "B.Mask" "B.Paste")
			(net "PVDDQ_DEF")
		)
		(pad "216" smd rect
			(at -4.59994 60.349892 270)
			(size 1.8034 0.508)
			(layers "B.Cu" "B.Mask" "B.Paste")
			(net "M_D_MA<2>")
		)
		(pad "217" smd rect
			(at -4.59994 61.20003 270)
			(size 1.8034 0.508)
			(layers "B.Cu" "B.Mask" "B.Paste")
			(net "PVDDQ_DEF")
		)
		(pad "218" smd rect
			(at -4.59994 62.049914 270)
			(size 1.8034 0.508)
			(layers "B.Cu" "B.Mask" "B.Paste")
			(net "M_D_CLK_DP<3>")
		)
		(pad "219" smd rect
			(at -4.59994 62.900052 270)
			(size 1.8034 0.508)
			(layers "B.Cu" "B.Mask" "B.Paste")
			(net "M_D_CLK_DN<3>")
		)
		(pad "220" smd rect
			(at -4.59994 63.749936 270)
			(size 1.8034 0.508)
			(layers "B.Cu" "B.Mask" "B.Paste")
			(net "PVDDQ_DEF")
		)
		(pad "221" smd rect
			(at -4.59994 64.600074 270)
			(size 1.8034 0.508)
			(layers "B.Cu" "B.Mask" "B.Paste")
			(net "PVTT_DEF")
		)
		(pad "222" smd rect
			(at -4.59994 70.550024 270)
			(size 1.8034 0.508)
			(layers "B.Cu" "B.Mask" "B.Paste")
			(net "M_D_PAR")
		)
		(pad "223" smd rect
			(at -4.59994 71.399908 270)
			(size 1.8034 0.508)
			(layers "B.Cu" "B.Mask" "B.Paste")
			(net "PVDDQ_DEF")
		)
		(pad "224" smd rect
			(at -4.59994 72.250046 270)
			(size 1.8034 0.508)
			(layers "B.Cu" "B.Mask" "B.Paste")
			(net "M_D_BA<1>")
		)
		(pad "225" smd rect
			(at -4.59994 73.09993 270)
			(size 1.8034 0.508)
			(layers "B.Cu" "B.Mask" "B.Paste")
			(net "M_D_MA<10>")
		)
		(pad "226" smd rect
			(at -4.59994 73.950068 270)
			(size 1.8034 0.508)
			(layers "B.Cu" "B.Mask" "B.Paste")
			(net "PVDDQ_DEF")
		)
		(pad "227" smd rect
			(at -4.59994 74.799952 270)
			(size 1.8034 0.508)
			(layers "B.Cu" "B.Mask" "B.Paste")
			(net "TP_CH_D_DIMM_D1_RFU_1")
		)
		(pad "228" smd rect
			(at -4.59994 75.65009 270)
			(size 1.8034 0.508)
			(layers "B.Cu" "B.Mask" "B.Paste")
			(net "M_D_MA<14>")
		)
		(pad "229" smd rect
			(at -4.59994 76.499974 270)
			(size 1.8034 0.508)
			(layers "B.Cu" "B.Mask" "B.Paste")
			(net "PVDDQ_DEF")
		)
		(pad "230" smd rect
			(at -4.59994 77.350112 270)
			(size 1.8034 0.508)
			(layers "B.Cu" "B.Mask" "B.Paste")
			(net "FM_ADR_COMPLETE_DEF_N")
		)
		(pad "231" smd rect
			(at -4.59994 78.199996 270)
			(size 1.8034 0.508)
			(layers "B.Cu" "B.Mask" "B.Paste")
			(net "PVDDQ_DEF")
		)
		(pad "232" smd rect
			(at -4.59994 79.04988 270)
			(size 1.8034 0.508)
			(layers "B.Cu" "B.Mask" "B.Paste")
			(net "M_D_MA<13>")
		)
		(pad "233" smd rect
			(at -4.59994 79.900018 270)
			(size 1.8034 0.508)
			(layers "B.Cu" "B.Mask" "B.Paste")
			(net "PVDDQ_DEF")
		)
		(pad "234" smd rect
			(at -4.59994 80.749902 270)
			(size 1.8034 0.508)
			(layers "B.Cu" "B.Mask" "B.Paste")
			(net "M_D_MA<17>")
		)
		(pad "235" smd rect
			(at -4.59994 81.60004 270)
			(size 1.8034 0.508)
			(layers "B.Cu" "B.Mask" "B.Paste")
			(net "M_D_C<2>")
		)
		(pad "236" smd rect
			(at -4.59994 82.449924 270)
			(size 1.8034 0.508)
			(layers "B.Cu" "B.Mask" "B.Paste")
			(net "PVDDQ_DEF")
		)
		(pad "237" smd rect
			(at -4.59994 83.300062 270)
			(size 1.8034 0.508)
			(layers "B.Cu" "B.Mask" "B.Paste")
			(net "M_D_CS_N<7>")
		)
		(pad "238" smd rect
			(at -4.59994 84.149946 270)
			(size 1.8034 0.508)
			(layers "B.Cu" "B.Mask" "B.Paste")
			(net "GND")
		)
		(pad "239" smd rect
			(at -4.59994 85.000084 270)
			(size 1.8034 0.508)
			(layers "B.Cu" "B.Mask" "B.Paste")
			(net "GND")
		)
		(pad "240" smd rect
			(at -4.59994 85.849968 270)
			(size 1.8034 0.508)
			(layers "B.Cu" "B.Mask" "B.Paste")
			(net "M_D_DQ<37>")
		)
	)
)
